FILE_TYPE = CONNECTIVITY;
{Allegro Design Entry HDL 17.4-2019 S026 (4007227) 1/17/2022}
"PAGE_NUMBER" = 393;
0"NC";
1"P5E_CPU1_P1_TX_BUF_DP<7:0>";
2"P5E_CPU1_P1_TX_BUF_C_DP<7:0>";
3"P5E_CPU1_P1_TX_BUF_DN<7:0>";
4"P5E_CPU1_P1_TX_BUF_C_DN<7:0>";
5"P5E_CPU1_P1_TX_BUF_DN<15:8>";
6"P5E_CPU1_P1_TX_BUF_DP<15:8>";
7"P5E_CPU1_P1_TX_BUF_C_DN<15:8>";
8"P5E_CPU1_P1_TX_BUF_C_DP<15:8>";
9"P5E_CPU1_P1_TX_BUF_DN<15:8>";
10"P5E_CPU1_P1_TX_BUF_DP<15:8>";
11"P5E_CPU1_P1_TX_BUF_DN<7:0>";
12"P5E_CPU1_P1_TX_BUF_DP<7:0>";
13"P5E_CPU1_P1_TX_BUF_DN<9>";
14"P5E_CPU1_P1_TX_BUF_DP<10>";
15"P5E_CPU1_P1_TX_BUF_DP<8>";
16"P5E_CPU1_P1_TX_BUF_DN<8>";
17"P5E_CPU1_P1_TX_BUF_DN<15>";
18"P5E_CPU1_P1_TX_BUF_DP<14>";
19"P5E_CPU1_P1_TX_BUF_DP<13>";
20"P5E_CPU1_P1_TX_BUF_DN<12>";
21"P5E_CPU1_P1_TX_BUF_DP<2>";
22"P5E_CPU1_P1_TX_BUF_DN<1>";
23"P5E_CPU1_P1_TX_BUF_DP<6>";
24"P5E_CPU1_P1_TX_BUF_DN<6>";
25"P5E_CPU1_P1_TX_BUF_DP<7>";
26"P5E_CPU1_P1_TX_BUF_DN<4>";
27"P5E_CPU1_P1_TX_BUF_DP<4>";
28"P5E_CPU1_P1_TX_BUF_DN<3>";
29"P5E_CPU1_P1_TX_BUF_DP<3>";
30"P5E_CPU1_P1_TX_BUF_DP<5>";
31"P5E_CPU1_P1_TX_BUF_DP<1>";
32"P5E_CPU1_P1_TX_BUF_DP<12>";
33"P5E_CPU1_P1_TX_BUF_DN<7>";
34"P5E_CPU1_P1_TX_BUF_DN<0>";
35"P5E_CPU1_P1_TX_BUF_DN<10>";
36"P5E_CPU1_P1_TX_BUF_DN<11>";
37"P5E_CPU1_P1_TX_BUF_DP<11>";
38"P5E_CPU1_P1_TX_BUF_DP<0>";
39"P5E_CPU1_P1_TX_BUF_DN<2>";
40"P5E_CPU1_P1_TX_BUF_DN<5>";
41"P5E_CPU1_P1_TX_BUF_DP<15>";
42"P5E_CPU1_P1_TX_BUF_DP<9>";
43"P5E_CPU1_P1_TX_BUF_DN<13>";
44"P5E_CPU1_P1_TX_BUF_DN<14>";
45"P5E_CPU1_P1_TX_BUF_C_DN<8>";
46"P5E_CPU1_P1_TX_BUF_C_DP<8>";
47"P5E_CPU1_P1_TX_BUF_DP<8>";
48"P5E_CPU1_P1_TX_BUF_DN<8>";
49"P5E_CPU1_P1_TX_BUF_C_DP<9>";
50"P5E_CPU1_P1_TX_BUF_C_DN<9>";
51"P5E_CPU1_P1_TX_BUF_C_DP<10>";
52"P5E_CPU1_P1_TX_BUF_C_DN<10>";
53"P5E_CPU1_P1_TX_BUF_C_DP<11>";
54"P5E_CPU1_P1_TX_BUF_C_DN<11>";
55"P5E_CPU1_P1_TX_BUF_C_DP<12>";
56"P5E_CPU1_P1_TX_BUF_C_DN<12>";
57"P5E_CPU1_P1_TX_BUF_C_DP<13>";
58"P5E_CPU1_P1_TX_BUF_C_DN<13>";
59"P5E_CPU1_P1_TX_BUF_DP<9>";
60"P5E_CPU1_P1_TX_BUF_DP<10>";
61"P5E_CPU1_P1_TX_BUF_DP<11>";
62"P5E_CPU1_P1_TX_BUF_DP<12>";
63"P5E_CPU1_P1_TX_BUF_DP<13>";
64"P5E_CPU1_P1_TX_BUF_C_DP<14>";
65"P5E_CPU1_P1_TX_BUF_C_DN<14>";
66"P5E_CPU1_P1_TX_BUF_C_DP<15>";
67"P5E_CPU1_P1_TX_BUF_C_DN<15>";
68"P5E_CPU1_P1_TX_BUF_DP<14>";
69"P5E_CPU1_P1_TX_BUF_DP<15>";
70"P5E_CPU1_P1_TX_BUF_DN<9>";
71"P5E_CPU1_P1_TX_BUF_DN<10>";
72"P5E_CPU1_P1_TX_BUF_DN<12>";
73"P5E_CPU1_P1_TX_BUF_DN<11>";
74"P5E_CPU1_P1_TX_BUF_DN<13>";
75"P5E_CPU1_P1_TX_BUF_DN<14>";
76"P5E_CPU1_P1_TX_BUF_DN<15>";
77"P5E_CPU1_P1_TX_BUF_C_DP<0>";
78"P5E_CPU1_P1_TX_BUF_C_DN<0>";
79"P5E_CPU1_P1_TX_BUF_C_DP<1>";
80"P5E_CPU1_P1_TX_BUF_C_DN<1>";
81"P5E_CPU1_P1_TX_BUF_C_DN<2>";
82"P5E_CPU1_P1_TX_BUF_C_DP<2>";
83"P5E_CPU1_P1_TX_BUF_C_DN<3>";
84"P5E_CPU1_P1_TX_BUF_C_DP<4>";
85"P5E_CPU1_P1_TX_BUF_C_DN<4>";
86"P5E_CPU1_P1_TX_BUF_C_DN<5>";
87"P5E_CPU1_P1_TX_BUF_C_DP<5>";
88"P5E_CPU1_P1_TX_BUF_C_DP<6>";
89"P5E_CPU1_P1_TX_BUF_C_DN<6>";
90"P5E_CPU1_P1_TX_BUF_C_DN<7>";
91"P5E_CPU1_P1_TX_BUF_C_DP<7>";
92"P5E_CPU1_P1_TX_BUF_DP<0>";
93"P5E_CPU1_P1_TX_BUF_DN<0>";
94"P5E_CPU1_P1_TX_BUF_DP<2>";
95"P5E_CPU1_P1_TX_BUF_DN<1>";
96"P5E_CPU1_P1_TX_BUF_DP<3>";
97"P5E_CPU1_P1_TX_BUF_DP<5>";
98"P5E_CPU1_P1_TX_BUF_DP<4>";
99"P5E_CPU1_P1_TX_BUF_DP<6>";
100"P5E_CPU1_P1_TX_BUF_DN<2>";
101"P5E_CPU1_P1_TX_BUF_DN<3>";
102"P5E_CPU1_P1_TX_BUF_DN<4>";
103"P5E_CPU1_P1_TX_BUF_DN<5>";
104"P5E_CPU1_P1_TX_BUF_DN<6>";
105"P5E_CPU1_P1_TX_BUF_DP<7>";
106"P5E_CPU1_P1_TX_BUF_DN<7>";
107"P5E_CPU1_P1_TX_BUF_C_DP<3>";
108"P5E_CPU1_P1_TX_BUF_DP<1>";
%"TAP"
"1","(-3350,1750)","2","standard","I10";
;
CDS_LIB"standard"
BODY_TYPE"PLUMBING"
HDL_TAP"TRUE";
"B \NAC \NWC"3;
"S \NAC"
BN"2"100;
%"Q_CAP_DIFFBUS"
"2","(-7000,1750)","2","pure_quanta","I100";
;
LOCATION"C6682"
$SEC"1"
CDS_SEC"1"
VALUE"DIFF BUS_0.22UF"
TOLERANCE"20%"
PACK_TYPE"C0201"
MATERIAL"X6S"
VOLTAGE"6.3V"
PIN_NAMES_ROTATE"TRUE"
CDS_LIB"pure_quanta"
CDS_LMAN_SYM_OUTLINE"-25,50,25,-50"
PART_NUMBER"SP_CH4221MEE01"
LOCATION"C6682";
"2"
$PN"2"71;
"1"
$PN"1"52;
%"Q_CAP_DIFFBUS"
"2","(-7000,2000)","2","pure_quanta","I101";
;
LOCATION"C6679"
$SEC"1"
CDS_SEC"1"
VALUE"DIFF BUS_0.22UF"
TOLERANCE"20%"
PACK_TYPE"C0201"
MATERIAL"X6S"
VOLTAGE"6.3V"
PIN_NAMES_ROTATE"TRUE"
CDS_LIB"pure_quanta"
CDS_LMAN_SYM_OUTLINE"-25,50,25,-50"
PART_NUMBER"SP_CH4221MEE01"
LOCATION"C6679";
"2"
$PN"2"59;
"1"
$PN"1"49;
%"Q_CAP_DIFFBUS"
"2","(-7000,1950)","2","pure_quanta","I102";
;
LOCATION"C6680"
$SEC"1"
CDS_SEC"1"
VALUE"DIFF BUS_0.22UF"
TOLERANCE"20%"
PACK_TYPE"C0201"
MATERIAL"X6S"
VOLTAGE"6.3V"
PIN_NAMES_ROTATE"TRUE"
CDS_LIB"pure_quanta"
CDS_LMAN_SYM_OUTLINE"-25,50,25,-50"
PART_NUMBER"SP_CH4221MEE01"
LOCATION"C6680";
"2"
$PN"2"70;
"1"
$PN"1"50;
%"Q_CAP_DIFFBUS"
"2","(-7000,2150)","2","pure_quanta","I103";
;
LOCATION"C6678"
$SEC"1"
CDS_SEC"1"
VALUE"DIFF BUS_0.22UF"
TOLERANCE"20%"
PACK_TYPE"C0201"
MATERIAL"X6S"
VOLTAGE"6.3V"
PIN_NAMES_ROTATE"TRUE"
CDS_LIB"pure_quanta"
CDS_LMAN_SYM_OUTLINE"-25,50,25,-50"
PART_NUMBER"SP_CH4221MEE01"
LOCATION"C6678";
"2"
$PN"2"48;
"1"
$PN"1"45;
%"Q_CAP_DIFFBUS"
"2","(-7000,2200)","2","pure_quanta","I104";
;
LOCATION"C6677"
$SEC"1"
CDS_SEC"1"
VALUE"DIFF BUS_0.22UF"
PACK_TYPE"C0201"
TOLERANCE"20%"
MATERIAL"X6S"
VOLTAGE"6.3V"
PIN_NAMES_ROTATE"TRUE"
CDS_LMAN_SYM_OUTLINE"-25,50,25,-50"
CDS_LIB"pure_quanta"
PART_NUMBER"SP_CH4221MEE01"
LOCATION"C6677";
"2"
$PN"2"47;
"1"
$PN"1"46;
%"TAP"
"1","(-7725,2200)","2","standard","I105";
;
CDS_LIB"standard"
BODY_TYPE"PLUMBING"
HDL_TAP"TRUE";
"B \NAC \NWC"6;
"S \NAC"
BN"8"47;
%"TAP"
"1","(-6450,800)","0","standard","I106";
;
CDS_LIB"standard"
BODY_TYPE"PLUMBING"
HDL_TAP"TRUE";
"B \NAC \NWC"8;
"S \NAC"
BN"15"66;
%"TAP"
"1","(-6250,750)","0","standard","I107";
;
CDS_LIB"standard"
BODY_TYPE"PLUMBING"
HDL_TAP"TRUE";
"B \NAC \NWC"7;
"S \NAC"
BN"15"67;
%"TAP"
"1","(-6450,1000)","0","standard","I108";
;
CDS_LIB"standard"
BODY_TYPE"PLUMBING"
HDL_TAP"TRUE";
"B \NAC \NWC"8;
"S \NAC"
BN"14"64;
%"TAP"
"1","(-6250,950)","0","standard","I109";
;
CDS_LIB"standard"
BODY_TYPE"PLUMBING"
HDL_TAP"TRUE";
"B \NAC \NWC"7;
"S \NAC"
BN"14"65;
%"TAP"
"1","(-3350,1950)","2","standard","I11";
;
CDS_LIB"standard"
BODY_TYPE"PLUMBING"
HDL_TAP"TRUE";
"B \NAC \NWC"3;
"S \NAC"
BN"1"95;
%"TAP"
"1","(-6250,1150)","0","standard","I110";
;
CDS_LIB"standard"
BODY_TYPE"PLUMBING"
HDL_TAP"TRUE";
"B \NAC \NWC"7;
"S \NAC"
BN"13"58;
%"TAP"
"1","(-6450,1200)","0","standard","I111";
;
CDS_LIB"standard"
BODY_TYPE"PLUMBING"
HDL_TAP"TRUE";
"B \NAC \NWC"8;
"S \NAC"
BN"13"57;
%"TAP"
"1","(-6450,1400)","0","standard","I112";
;
CDS_LIB"standard"
BODY_TYPE"PLUMBING"
HDL_TAP"TRUE";
"B \NAC \NWC"8;
"S \NAC"
BN"12"55;
%"TAP"
"1","(-6250,1350)","0","standard","I113";
;
CDS_LIB"standard"
BODY_TYPE"PLUMBING"
HDL_TAP"TRUE";
"B \NAC \NWC"7;
"S \NAC"
BN"12"56;
%"TAP"
"1","(-6250,1550)","0","standard","I114";
;
CDS_LIB"standard"
BODY_TYPE"PLUMBING"
HDL_TAP"TRUE";
"B \NAC \NWC"7;
"S \NAC"
BN"11"54;
%"TAP"
"1","(-6450,1600)","0","standard","I115";
;
CDS_LIB"standard"
BODY_TYPE"PLUMBING"
HDL_TAP"TRUE";
"B \NAC \NWC"8;
"S \NAC"
BN"11"53;
%"TAP"
"1","(-6450,1800)","0","standard","I116";
;
CDS_LIB"standard"
BODY_TYPE"PLUMBING"
HDL_TAP"TRUE";
"B \NAC \NWC"8;
"S \NAC"
BN"10"51;
%"TAP"
"1","(-6250,1750)","0","standard","I117";
;
CDS_LIB"standard"
BODY_TYPE"PLUMBING"
HDL_TAP"TRUE";
"B \NAC \NWC"7;
"S \NAC"
BN"10"52;
%"TAP"
"1","(-6450,2000)","0","standard","I118";
;
CDS_LIB"standard"
BODY_TYPE"PLUMBING"
HDL_TAP"TRUE";
"B \NAC \NWC"8;
"S \NAC"
BN"9"49;
%"TAP"
"1","(-6250,2150)","0","standard","I119";
;
CDS_LIB"standard"
BODY_TYPE"PLUMBING"
HDL_TAP"TRUE";
"B \NAC \NWC"7;
"S \NAC"
BN"8"45;
%"TAP"
"1","(-3100,1200)","2","standard","I12";
;
CDS_LIB"standard"
BODY_TYPE"PLUMBING"
HDL_TAP"TRUE";
"B \NAC \NWC"1;
"S \NAC"
BN"5"97;
%"TAP"
"1","(-6250,1950)","0","standard","I120";
;
CDS_LIB"standard"
BODY_TYPE"PLUMBING"
HDL_TAP"TRUE";
"B \NAC \NWC"7;
"S \NAC"
BN"9"50;
%"TAP"
"1","(-6450,2200)","0","standard","I123";
;
CDS_LIB"standard"
BODY_TYPE"PLUMBING"
HDL_TAP"TRUE";
"B \NAC \NWC"8;
"S \NAC"
BN"8"46;
%"TAP"
"1","(-1625,3350)","0","standard","I124";
;
CDS_LIB"standard"
BODY_TYPE"PLUMBING"
HDL_TAP"TRUE";
"B \NAC \NWC"12;
"S \NAC"
BN"0"38;
%"TAP"
"1","(-1425,3250)","0","standard","I125";
;
CDS_LIB"standard"
BODY_TYPE"PLUMBING"
HDL_TAP"TRUE";
"B \NAC \NWC"11;
"S \NAC"
BN"0"34;
%"TAP"
"1","(-1425,3600)","0","standard","I126";
;
CDS_LIB"standard"
BODY_TYPE"PLUMBING"
HDL_TAP"TRUE";
"B \NAC \NWC"11;
"S \NAC"
BN"1"22;
%"TAP"
"1","(-1625,3700)","0","standard","I127";
;
CDS_LIB"standard"
BODY_TYPE"PLUMBING"
HDL_TAP"TRUE";
"B \NAC \NWC"12;
"S \NAC"
BN"1"31;
%"TAP"
"1","(-1625,4050)","0","standard","I128";
;
CDS_LIB"standard"
BODY_TYPE"PLUMBING"
HDL_TAP"TRUE";
"B \NAC \NWC"12;
"S \NAC"
BN"2"21;
%"TAP"
"1","(-1425,3950)","0","standard","I129";
;
CDS_LIB"standard"
BODY_TYPE"PLUMBING"
HDL_TAP"TRUE";
"B \NAC \NWC"11;
"S \NAC"
BN"2"39;
%"TAP"
"1","(-3100,1400)","2","standard","I13";
;
CDS_LIB"standard"
BODY_TYPE"PLUMBING"
HDL_TAP"TRUE";
"B \NAC \NWC"1;
"S \NAC"
BN"4"98;
%"TAP"
"1","(-1625,4400)","0","standard","I130";
;
CDS_LIB"standard"
BODY_TYPE"PLUMBING"
HDL_TAP"TRUE";
"B \NAC \NWC"12;
"S \NAC"
BN"3"29;
%"TAP"
"1","(-1425,4300)","0","standard","I131";
;
CDS_LIB"standard"
BODY_TYPE"PLUMBING"
HDL_TAP"TRUE";
"B \NAC \NWC"11;
"S \NAC"
BN"3"28;
%"TAP"
"1","(-1425,4650)","0","standard","I132";
;
CDS_LIB"standard"
BODY_TYPE"PLUMBING"
HDL_TAP"TRUE";
"B \NAC \NWC"11;
"S \NAC"
BN"4"26;
%"TAP"
"1","(-1625,4750)","0","standard","I133";
;
CDS_LIB"standard"
BODY_TYPE"PLUMBING"
HDL_TAP"TRUE";
"B \NAC \NWC"12;
"S \NAC"
BN"4"27;
%"TAP"
"1","(-1625,5100)","0","standard","I134";
;
CDS_LIB"standard"
BODY_TYPE"PLUMBING"
HDL_TAP"TRUE";
"B \NAC \NWC"12;
"S \NAC"
BN"5"30;
%"TAP"
"1","(-1425,5000)","0","standard","I135";
;
CDS_LIB"standard"
BODY_TYPE"PLUMBING"
HDL_TAP"TRUE";
"B \NAC \NWC"11;
"S \NAC"
BN"5"40;
%"TAP"
"1","(-1625,5450)","0","standard","I136";
;
CDS_LIB"standard"
BODY_TYPE"PLUMBING"
HDL_TAP"TRUE";
"B \NAC \NWC"12;
"S \NAC"
BN"6"23;
%"TAP"
"1","(-1425,5350)","0","standard","I137";
;
CDS_LIB"standard"
BODY_TYPE"PLUMBING"
HDL_TAP"TRUE";
"B \NAC \NWC"11;
"S \NAC"
BN"6"24;
%"TAP"
"1","(-1425,5700)","0","standard","I138";
;
CDS_LIB"standard"
BODY_TYPE"PLUMBING"
HDL_TAP"TRUE";
"B \NAC \NWC"11;
"S \NAC"
BN"7"33;
%"TAP"
"1","(-1625,5800)","0","standard","I139";
;
CDS_LIB"standard"
BODY_TYPE"PLUMBING"
HDL_TAP"TRUE";
"B \NAC \NWC"12;
"S \NAC"
BN"7"25;
%"TAP"
"1","(-3100,1600)","2","standard","I14";
;
CDS_LIB"standard"
BODY_TYPE"PLUMBING"
HDL_TAP"TRUE";
"B \NAC \NWC"1;
"S \NAC"
BN"3"96;
%"PT5161LRS"
"11","(-2350,4550)","0","pure_quanta","I142";
;
LOCATION"U6015"
$SEC"11"
CDS_SEC"11"
PART_TYPE"SMLF"
VALUE"PT5161LRS"
MATERIAL"IC"
CDS_LIB"pure_quanta"
CDS_LMAN_SYM_OUTLINE"-350,1450,300,-1400"
NEEDS_NO_SIZE"TRUE"
PART_NUMBER"AJ051610U03";
"B_PETN15"
$PN"EW10"34;
"B_PETP15"
$PN"EU7"38;
"B_PETN14"
$PN"EM10"22;
"B_PETP14"
$PN"EK7"31;
"B_PETN13"
$PN"EE10"39;
"B_PETP13"
$PN"EC7"21;
"B_PETN12"
$PN"DV10"28;
"B_PETP12"
$PN"DT7"29;
"B_PETN11"
$PN"DL10"26;
"B_PETP11"
$PN"DJ7"27;
"B_PETN10"
$PN"DD10"40;
"B_PETP10"
$PN"DB7"30;
"B_PETN9"
$PN"CU10"24;
"B_PETP9"
$PN"CR7"23;
"B_PETN8"
$PN"CK10"33;
"B_PETP8"
$PN"CH7"25;
%"TAP"
"1","(-3100,1800)","2","standard","I15";
;
CDS_LIB"standard"
BODY_TYPE"PLUMBING"
HDL_TAP"TRUE";
"B \NAC \NWC"1;
"S \NAC"
BN"2"94;
%"TAP"
"1","(-3100,2000)","2","standard","I16";
;
CDS_LIB"standard"
BODY_TYPE"PLUMBING"
HDL_TAP"TRUE";
"B \NAC \NWC"1;
"S \NAC"
BN"1"108;
%"Q_CAP_DIFFBUS"
"2","(-2375,750)","2","pure_quanta","I17";
;
LOCATION"C6676"
$SEC"1"
CDS_SEC"1"
VALUE"DIFF BUS_0.22UF"
CDS_LMAN_SYM_OUTLINE"-25,50,25,-50"
CDS_LIB"pure_quanta"
PIN_NAMES_ROTATE"TRUE"
VOLTAGE"6.3V"
MATERIAL"X6S"
PACK_TYPE"C0201"
TOLERANCE"20%"
PART_NUMBER"SP_CH4221MEE01"
LOCATION"C6676";
"2"
$PN"2"106;
"1"
$PN"1"90;
%"Q_CAP_DIFFBUS"
"2","(-2375,800)","2","pure_quanta","I18";
;
LOCATION"C6675"
$SEC"1"
CDS_SEC"1"
VALUE"DIFF BUS_0.22UF"
CDS_LMAN_SYM_OUTLINE"-25,50,25,-50"
CDS_LIB"pure_quanta"
PIN_NAMES_ROTATE"TRUE"
VOLTAGE"6.3V"
MATERIAL"X6S"
PACK_TYPE"C0201"
TOLERANCE"20%"
PART_NUMBER"SP_CH4221MEE01"
LOCATION"C6675";
"2"
$PN"2"105;
"1"
$PN"1"91;
%"Q_CAP_DIFFBUS"
"2","(-2375,950)","2","pure_quanta","I19";
;
LOCATION"C6674"
$SEC"1"
CDS_SEC"1"
VALUE"DIFF BUS_0.22UF"
CDS_LMAN_SYM_OUTLINE"-25,50,25,-50"
CDS_LIB"pure_quanta"
PIN_NAMES_ROTATE"TRUE"
VOLTAGE"6.3V"
MATERIAL"X6S"
PACK_TYPE"C0201"
TOLERANCE"20%"
PART_NUMBER"SP_CH4221MEE01"
LOCATION"C6674";
"2"
$PN"2"104;
"1"
$PN"1"89;
%"Q_CAP_DIFFBUS"
"2","(-2375,1000)","2","pure_quanta","I20";
;
LOCATION"C6673"
$SEC"1"
CDS_SEC"1"
VALUE"DIFF BUS_0.22UF"
CDS_LIB"pure_quanta"
CDS_LMAN_SYM_OUTLINE"-25,50,25,-50"
PIN_NAMES_ROTATE"TRUE"
VOLTAGE"6.3V"
MATERIAL"X6S"
PACK_TYPE"C0201"
TOLERANCE"20%"
PART_NUMBER"SP_CH4221MEE01"
LOCATION"C6673";
"2"
$PN"2"99;
"1"
$PN"1"88;
%"TAP"
"1","(-1825,800)","0","standard","I21";
;
CDS_LIB"standard"
BODY_TYPE"PLUMBING"
HDL_TAP"TRUE";
"B \NAC \NWC"2;
"S \NAC"
BN"7"91;
%"TAP"
"1","(-1825,1000)","0","standard","I22";
;
CDS_LIB"standard"
BODY_TYPE"PLUMBING"
HDL_TAP"TRUE";
"B \NAC \NWC"2;
"S \NAC"
BN"6"88;
%"Q_CAP_DIFFBUS"
"2","(-2375,1150)","2","pure_quanta","I23";
;
LOCATION"C6672"
$SEC"1"
CDS_SEC"1"
VALUE"DIFF BUS_0.22UF"
CDS_LMAN_SYM_OUTLINE"-25,50,25,-50"
CDS_LIB"pure_quanta"
PIN_NAMES_ROTATE"TRUE"
VOLTAGE"6.3V"
MATERIAL"X6S"
PACK_TYPE"C0201"
TOLERANCE"20%"
PART_NUMBER"SP_CH4221MEE01"
LOCATION"C6672";
"2"
$PN"2"103;
"1"
$PN"1"86;
%"Q_CAP_DIFFBUS"
"2","(-2375,1200)","2","pure_quanta","I24";
;
LOCATION"C6671"
$SEC"1"
CDS_SEC"1"
VALUE"DIFF BUS_0.22UF"
CDS_LMAN_SYM_OUTLINE"-25,50,25,-50"
CDS_LIB"pure_quanta"
PIN_NAMES_ROTATE"TRUE"
VOLTAGE"6.3V"
MATERIAL"X6S"
PACK_TYPE"C0201"
TOLERANCE"20%"
PART_NUMBER"SP_CH4221MEE01"
LOCATION"C6671";
"2"
$PN"2"97;
"1"
$PN"1"87;
%"Q_CAP_DIFFBUS"
"2","(-2375,1350)","2","pure_quanta","I25";
;
LOCATION"C6670"
$SEC"1"
CDS_SEC"1"
VALUE"DIFF BUS_0.22UF"
CDS_LIB"pure_quanta"
CDS_LMAN_SYM_OUTLINE"-25,50,25,-50"
PIN_NAMES_ROTATE"TRUE"
VOLTAGE"6.3V"
MATERIAL"X6S"
PACK_TYPE"C0201"
TOLERANCE"20%"
PART_NUMBER"SP_CH4221MEE01"
LOCATION"C6670";
"2"
$PN"2"102;
"1"
$PN"1"85;
%"Q_CAP_DIFFBUS"
"2","(-2375,1400)","2","pure_quanta","I26";
;
LOCATION"C6669"
$SEC"1"
CDS_SEC"1"
VALUE"DIFF BUS_0.22UF"
CDS_LIB"pure_quanta"
CDS_LMAN_SYM_OUTLINE"-25,50,25,-50"
PIN_NAMES_ROTATE"TRUE"
VOLTAGE"6.3V"
MATERIAL"X6S"
PACK_TYPE"C0201"
TOLERANCE"20%"
PART_NUMBER"SP_CH4221MEE01"
LOCATION"C6669";
"2"
$PN"2"98;
"1"
$PN"1"84;
%"Q_CAP_DIFFBUS"
"2","(-2375,1600)","2","pure_quanta","I27";
;
LOCATION"C6667"
$SEC"1"
CDS_SEC"1"
VALUE"DIFF BUS_0.22UF"
CDS_LMAN_SYM_OUTLINE"-25,50,25,-50"
CDS_LIB"pure_quanta"
PIN_NAMES_ROTATE"TRUE"
VOLTAGE"6.3V"
MATERIAL"X6S"
PACK_TYPE"C0201"
TOLERANCE"20%"
PART_NUMBER"SP_CH4221MEE01"
LOCATION"C6667";
"2"
$PN"2"96;
"1"
$PN"1"107;
%"Q_CAP_DIFFBUS"
"2","(-2375,1550)","2","pure_quanta","I28";
;
LOCATION"C6668"
$SEC"1"
CDS_SEC"1"
VALUE"DIFF BUS_0.22UF"
CDS_LMAN_SYM_OUTLINE"-25,50,25,-50"
CDS_LIB"pure_quanta"
PIN_NAMES_ROTATE"TRUE"
VOLTAGE"6.3V"
MATERIAL"X6S"
PACK_TYPE"C0201"
TOLERANCE"20%"
PART_NUMBER"SP_CH4221MEE01"
LOCATION"C6668";
"2"
$PN"2"101;
"1"
$PN"1"83;
%"Q_CAP_DIFFBUS"
"2","(-2375,1750)","2","pure_quanta","I29";
;
LOCATION"C6666"
$SEC"1"
CDS_SEC"1"
VALUE"DIFF BUS_0.22UF"
CDS_LMAN_SYM_OUTLINE"-25,50,25,-50"
CDS_LIB"pure_quanta"
PIN_NAMES_ROTATE"TRUE"
VOLTAGE"6.3V"
MATERIAL"X6S"
PACK_TYPE"C0201"
TOLERANCE"20%"
PART_NUMBER"SP_CH4221MEE01"
LOCATION"C6666";
"2"
$PN"2"100;
"1"
$PN"1"81;
%"TAP"
"1","(-3350,750)","2","standard","I3";
;
CDS_LIB"standard"
BODY_TYPE"PLUMBING"
HDL_TAP"TRUE";
"B \NAC \NWC"3;
"S \NAC"
BN"7"106;
%"Q_CAP_DIFFBUS"
"2","(-2375,1800)","2","pure_quanta","I30";
;
LOCATION"C6665"
$SEC"1"
CDS_SEC"1"
VALUE"DIFF BUS_0.22UF"
CDS_LMAN_SYM_OUTLINE"-25,50,25,-50"
CDS_LIB"pure_quanta"
PIN_NAMES_ROTATE"TRUE"
VOLTAGE"6.3V"
MATERIAL"X6S"
PACK_TYPE"C0201"
TOLERANCE"20%"
PART_NUMBER"SP_CH4221MEE01"
LOCATION"C6665";
"2"
$PN"2"94;
"1"
$PN"1"82;
%"Q_CAP_DIFFBUS"
"2","(-2375,2000)","2","pure_quanta","I31";
;
LOCATION"C6663"
$SEC"1"
CDS_SEC"1"
VALUE"DIFF BUS_0.22UF"
CDS_LMAN_SYM_OUTLINE"-25,50,25,-50"
CDS_LIB"pure_quanta"
PIN_NAMES_ROTATE"TRUE"
VOLTAGE"6.3V"
MATERIAL"X6S"
PACK_TYPE"C0201"
TOLERANCE"20%"
PART_NUMBER"SP_CH4221MEE01"
LOCATION"C6663";
"2"
$PN"2"108;
"1"
$PN"1"79;
%"Q_CAP_DIFFBUS"
"2","(-2375,1950)","2","pure_quanta","I32";
;
LOCATION"C6664"
$SEC"1"
CDS_SEC"1"
VALUE"DIFF BUS_0.22UF"
CDS_LMAN_SYM_OUTLINE"-25,50,25,-50"
CDS_LIB"pure_quanta"
PIN_NAMES_ROTATE"TRUE"
VOLTAGE"6.3V"
MATERIAL"X6S"
PACK_TYPE"C0201"
TOLERANCE"20%"
PART_NUMBER"SP_CH4221MEE01"
LOCATION"C6664";
"2"
$PN"2"95;
"1"
$PN"1"80;
%"Q_CAP_DIFFBUS"
"2","(-2375,2150)","2","pure_quanta","I33";
;
LOCATION"C6662"
$SEC"1"
CDS_SEC"1"
VALUE"DIFF BUS_0.22UF"
CDS_LMAN_SYM_OUTLINE"-25,50,25,-50"
CDS_LIB"pure_quanta"
PIN_NAMES_ROTATE"TRUE"
VOLTAGE"6.3V"
MATERIAL"X6S"
PACK_TYPE"C0201"
TOLERANCE"20%"
PART_NUMBER"SP_CH4221MEE01"
LOCATION"C6662";
"2"
$PN"2"93;
"1"
$PN"1"78;
%"TAP"
"1","(-1825,1200)","0","standard","I34";
;
CDS_LIB"standard"
BODY_TYPE"PLUMBING"
HDL_TAP"TRUE";
"B \NAC \NWC"2;
"S \NAC"
BN"5"87;
%"TAP"
"1","(-1825,1600)","0","standard","I35";
;
CDS_LIB"standard"
BODY_TYPE"PLUMBING"
HDL_TAP"TRUE";
"B \NAC \NWC"2;
"S \NAC"
BN"3"107;
%"TAP"
"1","(-1825,1400)","0","standard","I36";
;
CDS_LIB"standard"
BODY_TYPE"PLUMBING"
HDL_TAP"TRUE";
"B \NAC \NWC"2;
"S \NAC"
BN"4"84;
%"TAP"
"1","(-1825,1800)","0","standard","I37";
;
CDS_LIB"standard"
BODY_TYPE"PLUMBING"
HDL_TAP"TRUE";
"B \NAC \NWC"2;
"S \NAC"
BN"2"82;
%"TAP"
"1","(-1825,2000)","0","standard","I38";
;
CDS_LIB"standard"
BODY_TYPE"PLUMBING"
HDL_TAP"TRUE";
"B \NAC \NWC"2;
"S \NAC"
BN"1"79;
%"TAP"
"1","(-3350,2150)","2","standard","I39";
;
CDS_LIB"standard"
BODY_TYPE"PLUMBING"
HDL_TAP"TRUE";
"B \NAC \NWC"3;
"S \NAC"
BN"0"93;
%"TAP"
"1","(-3350,950)","2","standard","I4";
;
CDS_LIB"standard"
BODY_TYPE"PLUMBING"
HDL_TAP"TRUE";
"B \NAC \NWC"3;
"S \NAC"
BN"6"104;
%"TAP"
"1","(-3100,2200)","2","standard","I40";
;
CDS_LIB"standard"
BODY_TYPE"PLUMBING"
HDL_TAP"TRUE";
"B \NAC \NWC"1;
"S \NAC"
BN"0"92;
%"PT5161LRS"
"10","(-7525,4575)","0","pure_quanta","I41";
;
LOCATION"U6015"
$SEC"10"
CDS_SEC"10"
MATERIAL"IC"
VALUE"PT5161LRS"
PART_TYPE"SMLF"
NEEDS_NO_SIZE"TRUE"
CDS_LMAN_SYM_OUTLINE"-350,1450,300,-1400"
CDS_LIB"pure_quanta"
PART_NUMBER"AJ051610U03";
"B_PETN7"
$PN"CC10"16;
"B_PETP7"
$PN"CA7"15;
"B_PETN6"
$PN"BT10"13;
"B_PETP6"
$PN"BP7"42;
"B_PETN5"
$PN"BJ10"35;
"B_PETP5"
$PN"BG7"14;
"B_PETN4"
$PN"BB10"36;
"B_PETP4"
$PN"AY7"37;
"B_PETN3"
$PN"AR10"20;
"B_PETP3"
$PN"AN7"32;
"B_PETN2"
$PN"AH10"43;
"B_PETP2"
$PN"AF7"19;
"B_PETN1"
$PN"AA10"44;
"B_PETP1"
$PN"W7"18;
"B_PETN0"
$PN"P10"17;
"B_PETP0"
$PN"M7"41;
%"Q_CAP_DIFFBUS"
"2","(-2375,2200)","2","pure_quanta","I42";
;
LOCATION"C6661"
$SEC"1"
CDS_SEC"1"
PACK_TYPE"C0201"
TOLERANCE"20%"
MATERIAL"X6S"
VOLTAGE"6.3V"
VALUE"DIFF BUS_0.22UF"
CDS_LIB"pure_quanta"
CDS_LMAN_SYM_OUTLINE"-25,50,25,-50"
PIN_NAMES_ROTATE"TRUE"
PART_NUMBER"SP_CH4221MEE01"
LOCATION"C6661";
"2"
$PN"2"92;
"1"
$PN"1"77;
%"TAP"
"1","(-1825,2200)","0","standard","I43";
;
CDS_LIB"standard"
BODY_TYPE"PLUMBING"
HDL_TAP"TRUE";
"B \NAC \NWC"2;
"S \NAC"
BN"0"77;
%"TAP"
"1","(-6800,3375)","0","standard","I44";
;
CDS_LIB"standard"
BODY_TYPE"PLUMBING"
HDL_TAP"TRUE";
"B \NAC \NWC"10;
"S \NAC"
BN"8"15;
%"TAP"
"1","(-6600,3275)","0","standard","I45";
;
CDS_LIB"standard"
BODY_TYPE"PLUMBING"
HDL_TAP"TRUE";
"B \NAC \NWC"9;
"S \NAC"
BN"8"16;
%"TAP"
"1","(-6600,3625)","0","standard","I46";
;
CDS_LIB"standard"
BODY_TYPE"PLUMBING"
HDL_TAP"TRUE";
"B \NAC \NWC"9;
"S \NAC"
BN"9"13;
%"TAP"
"1","(-6800,3725)","0","standard","I47";
;
CDS_LIB"standard"
BODY_TYPE"PLUMBING"
HDL_TAP"TRUE";
"B \NAC \NWC"10;
"S \NAC"
BN"9"42;
%"TAP"
"1","(-6800,4075)","0","standard","I48";
;
CDS_LIB"standard"
BODY_TYPE"PLUMBING"
HDL_TAP"TRUE";
"B \NAC \NWC"10;
"S \NAC"
BN"10"14;
%"TAP"
"1","(-6600,3975)","0","standard","I49";
;
CDS_LIB"standard"
BODY_TYPE"PLUMBING"
HDL_TAP"TRUE";
"B \NAC \NWC"9;
"S \NAC"
BN"10"35;
%"TAP"
"1","(-3100,800)","2","standard","I5";
;
CDS_LIB"standard"
BODY_TYPE"PLUMBING"
HDL_TAP"TRUE";
"B \NAC \NWC"1;
"S \NAC"
BN"7"105;
%"TAP"
"1","(-1625,750)","0","standard","I50";
;
CDS_LIB"standard"
BODY_TYPE"PLUMBING"
HDL_TAP"TRUE";
"B \NAC \NWC"4;
"S \NAC"
BN"7"90;
%"TAP"
"1","(-1625,950)","0","standard","I51";
;
CDS_LIB"standard"
BODY_TYPE"PLUMBING"
HDL_TAP"TRUE";
"B \NAC \NWC"4;
"S \NAC"
BN"6"89;
%"TAP"
"1","(-1625,1150)","0","standard","I52";
;
CDS_LIB"standard"
BODY_TYPE"PLUMBING"
HDL_TAP"TRUE";
"B \NAC \NWC"4;
"S \NAC"
BN"5"86;
%"TAP"
"1","(-1625,1350)","0","standard","I53";
;
CDS_LIB"standard"
BODY_TYPE"PLUMBING"
HDL_TAP"TRUE";
"B \NAC \NWC"4;
"S \NAC"
BN"4"85;
%"TAP"
"1","(-1625,1550)","0","standard","I54";
;
CDS_LIB"standard"
BODY_TYPE"PLUMBING"
HDL_TAP"TRUE";
"B \NAC \NWC"4;
"S \NAC"
BN"3"83;
%"TAP"
"1","(-1625,1750)","0","standard","I55";
;
CDS_LIB"standard"
BODY_TYPE"PLUMBING"
HDL_TAP"TRUE";
"B \NAC \NWC"4;
"S \NAC"
BN"2"81;
%"TAP"
"1","(-1625,1950)","0","standard","I56";
;
CDS_LIB"standard"
BODY_TYPE"PLUMBING"
HDL_TAP"TRUE";
"B \NAC \NWC"4;
"S \NAC"
BN"1"80;
%"TAP"
"1","(-3100,1000)","2","standard","I6";
;
CDS_LIB"standard"
BODY_TYPE"PLUMBING"
HDL_TAP"TRUE";
"B \NAC \NWC"1;
"S \NAC"
BN"6"99;
%"TAP"
"1","(-1625,2150)","0","standard","I60";
;
CDS_LIB"standard"
BODY_TYPE"PLUMBING"
HDL_TAP"TRUE";
"B \NAC \NWC"4;
"S \NAC"
BN"0"78;
%"TAP"
"1","(-6800,4425)","0","standard","I62";
;
CDS_LIB"standard"
BODY_TYPE"PLUMBING"
HDL_TAP"TRUE";
"B \NAC \NWC"10;
"S \NAC"
BN"11"37;
%"TAP"
"1","(-6600,4325)","0","standard","I63";
;
CDS_LIB"standard"
BODY_TYPE"PLUMBING"
HDL_TAP"TRUE";
"B \NAC \NWC"9;
"S \NAC"
BN"11"36;
%"TAP"
"1","(-6600,4675)","0","standard","I64";
;
CDS_LIB"standard"
BODY_TYPE"PLUMBING"
HDL_TAP"TRUE";
"B \NAC \NWC"9;
"S \NAC"
BN"12"20;
%"TAP"
"1","(-6800,4775)","0","standard","I65";
;
CDS_LIB"standard"
BODY_TYPE"PLUMBING"
HDL_TAP"TRUE";
"B \NAC \NWC"10;
"S \NAC"
BN"12"32;
%"TAP"
"1","(-6800,5125)","0","standard","I66";
;
CDS_LIB"standard"
BODY_TYPE"PLUMBING"
HDL_TAP"TRUE";
"B \NAC \NWC"10;
"S \NAC"
BN"13"19;
%"TAP"
"1","(-6600,5025)","0","standard","I67";
;
CDS_LIB"standard"
BODY_TYPE"PLUMBING"
HDL_TAP"TRUE";
"B \NAC \NWC"9;
"S \NAC"
BN"13"43;
%"TAP"
"1","(-6800,5475)","0","standard","I68";
;
CDS_LIB"standard"
BODY_TYPE"PLUMBING"
HDL_TAP"TRUE";
"B \NAC \NWC"10;
"S \NAC"
BN"14"18;
%"TAP"
"1","(-6600,5375)","0","standard","I69";
;
CDS_LIB"standard"
BODY_TYPE"PLUMBING"
HDL_TAP"TRUE";
"B \NAC \NWC"9;
"S \NAC"
BN"14"44;
%"TAP"
"1","(-3350,1150)","2","standard","I7";
;
CDS_LIB"standard"
BODY_TYPE"PLUMBING"
HDL_TAP"TRUE";
"B \NAC \NWC"3;
"S \NAC"
BN"5"103;
%"TAP"
"1","(-6600,5725)","0","standard","I70";
;
CDS_LIB"standard"
BODY_TYPE"PLUMBING"
HDL_TAP"TRUE";
"B \NAC \NWC"9;
"S \NAC"
BN"15"17;
%"TAP"
"1","(-6800,5825)","0","standard","I71";
;
CDS_LIB"standard"
BODY_TYPE"PLUMBING"
HDL_TAP"TRUE";
"B \NAC \NWC"10;
"S \NAC"
BN"15"41;
%"TAP"
"1","(-7975,750)","2","standard","I74";
;
CDS_LIB"standard"
BODY_TYPE"PLUMBING"
HDL_TAP"TRUE";
"B \NAC \NWC"5;
"S \NAC"
BN"15"76;
%"TAP"
"1","(-7975,950)","2","standard","I75";
;
CDS_LIB"standard"
BODY_TYPE"PLUMBING"
HDL_TAP"TRUE";
"B \NAC \NWC"5;
"S \NAC"
BN"14"75;
%"TAP"
"1","(-7975,1150)","2","standard","I76";
;
CDS_LIB"standard"
BODY_TYPE"PLUMBING"
HDL_TAP"TRUE";
"B \NAC \NWC"5;
"S \NAC"
BN"13"74;
%"TAP"
"1","(-7975,1350)","2","standard","I77";
;
CDS_LIB"standard"
BODY_TYPE"PLUMBING"
HDL_TAP"TRUE";
"B \NAC \NWC"5;
"S \NAC"
BN"12"72;
%"TAP"
"1","(-7975,1550)","2","standard","I78";
;
CDS_LIB"standard"
BODY_TYPE"PLUMBING"
HDL_TAP"TRUE";
"B \NAC \NWC"5;
"S \NAC"
BN"11"73;
%"TAP"
"1","(-7975,1750)","2","standard","I79";
;
CDS_LIB"standard"
BODY_TYPE"PLUMBING"
HDL_TAP"TRUE";
"B \NAC \NWC"5;
"S \NAC"
BN"10"71;
%"TAP"
"1","(-3350,1350)","2","standard","I8";
;
CDS_LIB"standard"
BODY_TYPE"PLUMBING"
HDL_TAP"TRUE";
"B \NAC \NWC"3;
"S \NAC"
BN"4"102;
%"TAP"
"1","(-7975,1950)","2","standard","I80";
;
CDS_LIB"standard"
BODY_TYPE"PLUMBING"
HDL_TAP"TRUE";
"B \NAC \NWC"5;
"S \NAC"
BN"9"70;
%"TAP"
"1","(-7975,2150)","2","standard","I81";
;
CDS_LIB"standard"
BODY_TYPE"PLUMBING"
HDL_TAP"TRUE";
"B \NAC \NWC"5;
"S \NAC"
BN"8"48;
%"TAP"
"1","(-7725,800)","2","standard","I82";
;
CDS_LIB"standard"
BODY_TYPE"PLUMBING"
HDL_TAP"TRUE";
"B \NAC \NWC"6;
"S \NAC"
BN"15"69;
%"TAP"
"1","(-7725,1000)","2","standard","I83";
;
CDS_LIB"standard"
BODY_TYPE"PLUMBING"
HDL_TAP"TRUE";
"B \NAC \NWC"6;
"S \NAC"
BN"14"68;
%"Q_CAP_DIFFBUS"
"2","(-7000,750)","2","pure_quanta","I84";
;
LOCATION"C6692"
$SEC"1"
CDS_SEC"1"
VALUE"DIFF BUS_0.22UF"
TOLERANCE"20%"
PACK_TYPE"C0201"
MATERIAL"X6S"
VOLTAGE"6.3V"
PIN_NAMES_ROTATE"TRUE"
CDS_LIB"pure_quanta"
CDS_LMAN_SYM_OUTLINE"-25,50,25,-50"
PART_NUMBER"SP_CH4221MEE01"
LOCATION"C6692";
"2"
$PN"2"76;
"1"
$PN"1"67;
%"Q_CAP_DIFFBUS"
"2","(-7000,800)","2","pure_quanta","I85";
;
LOCATION"C6691"
$SEC"1"
CDS_SEC"1"
VALUE"DIFF BUS_0.22UF"
TOLERANCE"20%"
PACK_TYPE"C0201"
MATERIAL"X6S"
VOLTAGE"6.3V"
PIN_NAMES_ROTATE"TRUE"
CDS_LIB"pure_quanta"
CDS_LMAN_SYM_OUTLINE"-25,50,25,-50"
PART_NUMBER"SP_CH4221MEE01"
LOCATION"C6691";
"2"
$PN"2"69;
"1"
$PN"1"66;
%"Q_CAP_DIFFBUS"
"2","(-7000,950)","2","pure_quanta","I86";
;
LOCATION"C6690"
$SEC"1"
CDS_SEC"1"
VALUE"DIFF BUS_0.22UF"
TOLERANCE"20%"
PACK_TYPE"C0201"
MATERIAL"X6S"
VOLTAGE"6.3V"
PIN_NAMES_ROTATE"TRUE"
CDS_LIB"pure_quanta"
CDS_LMAN_SYM_OUTLINE"-25,50,25,-50"
PART_NUMBER"SP_CH4221MEE01"
LOCATION"C6690";
"2"
$PN"2"75;
"1"
$PN"1"65;
%"Q_CAP_DIFFBUS"
"2","(-7000,1000)","2","pure_quanta","I87";
;
LOCATION"C6689"
$SEC"1"
CDS_SEC"1"
VALUE"DIFF BUS_0.22UF"
TOLERANCE"20%"
PACK_TYPE"C0201"
MATERIAL"X6S"
VOLTAGE"6.3V"
PIN_NAMES_ROTATE"TRUE"
CDS_LMAN_SYM_OUTLINE"-25,50,25,-50"
CDS_LIB"pure_quanta"
PART_NUMBER"SP_CH4221MEE01"
LOCATION"C6689";
"2"
$PN"2"68;
"1"
$PN"1"64;
%"Q_CAP_DIFFBUS"
"2","(-7000,1150)","2","pure_quanta","I88";
;
LOCATION"C6688"
$SEC"1"
CDS_SEC"1"
VALUE"DIFF BUS_0.22UF"
TOLERANCE"20%"
PACK_TYPE"C0201"
MATERIAL"X6S"
VOLTAGE"6.3V"
PIN_NAMES_ROTATE"TRUE"
CDS_LIB"pure_quanta"
CDS_LMAN_SYM_OUTLINE"-25,50,25,-50"
PART_NUMBER"SP_CH4221MEE01"
LOCATION"C6688";
"2"
$PN"2"74;
"1"
$PN"1"58;
%"Q_CAP_DIFFBUS"
"2","(-7000,1200)","2","pure_quanta","I89";
;
LOCATION"C6687"
$SEC"1"
CDS_SEC"1"
VALUE"DIFF BUS_0.22UF"
TOLERANCE"20%"
PACK_TYPE"C0201"
MATERIAL"X6S"
VOLTAGE"6.3V"
PIN_NAMES_ROTATE"TRUE"
CDS_LIB"pure_quanta"
CDS_LMAN_SYM_OUTLINE"-25,50,25,-50"
PART_NUMBER"SP_CH4221MEE01"
LOCATION"C6687";
"2"
$PN"2"63;
"1"
$PN"1"57;
%"TAP"
"1","(-3350,1550)","2","standard","I9";
;
CDS_LIB"standard"
BODY_TYPE"PLUMBING"
HDL_TAP"TRUE";
"B \NAC \NWC"3;
"S \NAC"
BN"3"101;
%"TAP"
"1","(-7725,1200)","2","standard","I90";
;
CDS_LIB"standard"
BODY_TYPE"PLUMBING"
HDL_TAP"TRUE";
"B \NAC \NWC"6;
"S \NAC"
BN"13"63;
%"TAP"
"1","(-7725,1400)","2","standard","I91";
;
CDS_LIB"standard"
BODY_TYPE"PLUMBING"
HDL_TAP"TRUE";
"B \NAC \NWC"6;
"S \NAC"
BN"12"62;
%"TAP"
"1","(-7725,1600)","2","standard","I92";
;
CDS_LIB"standard"
BODY_TYPE"PLUMBING"
HDL_TAP"TRUE";
"B \NAC \NWC"6;
"S \NAC"
BN"11"61;
%"TAP"
"1","(-7725,1800)","2","standard","I93";
;
CDS_LIB"standard"
BODY_TYPE"PLUMBING"
HDL_TAP"TRUE";
"B \NAC \NWC"6;
"S \NAC"
BN"10"60;
%"TAP"
"1","(-7725,2000)","2","standard","I94";
;
CDS_LIB"standard"
BODY_TYPE"PLUMBING"
HDL_TAP"TRUE";
"B \NAC \NWC"6;
"S \NAC"
BN"9"59;
%"Q_CAP_DIFFBUS"
"2","(-7000,1350)","2","pure_quanta","I95";
;
LOCATION"C6686"
$SEC"1"
CDS_SEC"1"
VALUE"DIFF BUS_0.22UF"
TOLERANCE"20%"
PACK_TYPE"C0201"
MATERIAL"X6S"
VOLTAGE"6.3V"
PIN_NAMES_ROTATE"TRUE"
CDS_LMAN_SYM_OUTLINE"-25,50,25,-50"
CDS_LIB"pure_quanta"
PART_NUMBER"SP_CH4221MEE01"
LOCATION"C6686";
"2"
$PN"2"72;
"1"
$PN"1"56;
%"Q_CAP_DIFFBUS"
"2","(-7000,1400)","2","pure_quanta","I96";
;
LOCATION"C6685"
$SEC"1"
CDS_SEC"1"
VALUE"DIFF BUS_0.22UF"
TOLERANCE"20%"
PACK_TYPE"C0201"
MATERIAL"X6S"
VOLTAGE"6.3V"
PIN_NAMES_ROTATE"TRUE"
CDS_LMAN_SYM_OUTLINE"-25,50,25,-50"
CDS_LIB"pure_quanta"
PART_NUMBER"SP_CH4221MEE01"
LOCATION"C6685";
"2"
$PN"2"62;
"1"
$PN"1"55;
%"Q_CAP_DIFFBUS"
"2","(-7000,1550)","2","pure_quanta","I97";
;
LOCATION"C6684"
$SEC"1"
CDS_SEC"1"
VALUE"DIFF BUS_0.22UF"
TOLERANCE"20%"
PACK_TYPE"C0201"
MATERIAL"X6S"
VOLTAGE"6.3V"
PIN_NAMES_ROTATE"TRUE"
CDS_LIB"pure_quanta"
CDS_LMAN_SYM_OUTLINE"-25,50,25,-50"
PART_NUMBER"SP_CH4221MEE01"
LOCATION"C6684";
"2"
$PN"2"73;
"1"
$PN"1"54;
%"Q_CAP_DIFFBUS"
"2","(-7000,1600)","2","pure_quanta","I98";
;
LOCATION"C6683"
$SEC"1"
CDS_SEC"1"
VALUE"DIFF BUS_0.22UF"
TOLERANCE"20%"
PACK_TYPE"C0201"
MATERIAL"X6S"
VOLTAGE"6.3V"
PIN_NAMES_ROTATE"TRUE"
CDS_LIB"pure_quanta"
CDS_LMAN_SYM_OUTLINE"-25,50,25,-50"
PART_NUMBER"SP_CH4221MEE01"
LOCATION"C6683";
"2"
$PN"2"61;
"1"
$PN"1"53;
%"Q_CAP_DIFFBUS"
"2","(-7000,1800)","2","pure_quanta","I99";
;
LOCATION"C6681"
$SEC"1"
CDS_SEC"1"
VALUE"DIFF BUS_0.22UF"
TOLERANCE"20%"
PACK_TYPE"C0201"
MATERIAL"X6S"
VOLTAGE"6.3V"
PIN_NAMES_ROTATE"TRUE"
CDS_LIB"pure_quanta"
CDS_LMAN_SYM_OUTLINE"-25,50,25,-50"
PART_NUMBER"SP_CH4221MEE01"
LOCATION"C6681";
"2"
$PN"2"60;
"1"
$PN"1"51;
END.
